(kicad_pcb
	(version 20260206)
	(generator "pcbnew")
	(generator_version "10.0")
	(general
		(thickness 1.6)
		(legacy_teardrops no)
	)
	(paper "A4")
	(title_block
		(title "04192023_DAF0TMB3IC0_F0TG_MB_C_brd_V02_OCP.brd")
		(comment 1 "Grand Teton / footprint 3955 of 8354 (U25), pads 435-540 of 6102")
	)
	(layers
		(0 "F.Cu" signal "TOP")
		(4 "In1.Cu" signal "GND")
		(6 "In2.Cu" signal "IN1")
		(8 "In3.Cu" signal "GND1")
		(10 "In4.Cu" signal "IN2")
		(12 "In5.Cu" signal "GND2")
		(14 "In6.Cu" signal "IN3")
		(16 "In7.Cu" signal "GND3")
		(18 "In8.Cu" signal "VCC")
		(20 "In9.Cu" signal "VCC1")
		(22 "In10.Cu" signal "GND4")
		(24 "In11.Cu" signal "IN4")
		(26 "In12.Cu" signal "GND5")
		(28 "In13.Cu" signal "IN5")
		(30 "In14.Cu" signal "GND6")
		(32 "In15.Cu" signal "IN6")
		(34 "In16.Cu" signal "GND7")
		(2 "B.Cu" signal "BOTTOM")
		(9 "F.Adhes" user "F.Adhesive")
		(11 "B.Adhes" user "B.Adhesive")
		(13 "F.Paste" user "Package Geometry/Pastemask Top")
		(15 "B.Paste" user "Package Geometry/Pastemask Bottom")
		(5 "F.SilkS" user "Ref Des/Silkscreen Top")
		(7 "B.SilkS" user "Ref Des/Silkscreen Bottom")
		(1 "F.Mask" user "Board Geometry/Soldermask Top")
		(3 "B.Mask" user "Board Geometry/Soldermask Bottom")
		(17 "Dwgs.User" user "User.Drawings")
		(19 "Cmts.User" user "User.Comments")
		(21 "Eco1.User" user "User.Eco1")
		(23 "Eco2.User" user "User.Eco2")
		(25 "Edge.Cuts" user "Board Geometry/Outline")
		(27 "Margin" user)
		(31 "F.CrtYd" user "Package Geometry/Place Bound Top")
		(29 "B.CrtYd" user "Package Geometry/Place Bound Bottom")
		(35 "F.Fab" user "Ref Des/Assembly Top")
		(33 "B.Fab" user "Ref Des/Assembly Bottom")
	)
	(footprint ""
		(layer "F.Cu")
		(at 359.867962 -258.880102 180)
		(property "Reference" "U25"
			(at -45.78477 -62.086744 0)
			(unlocked yes)
			(layer "F.SilkS")
			(effects
				(font
					(size 0.7874 0.5842)
					(thickness 0.1524)
				)
			)
		)
		(property "Value" ""
			(at 0 0 180)
			(layer "F.Fab")
			(effects
				(font
					(size 1.27 1.27)
				)
			)
		)
		(duplicate_pad_numbers_are_jumpers no)
		(pad "AF14" smd circle
			(at -22.409912 -16.560038 180)
			(size 0.450088 0.450088)
			(layers "F.Cu" "F.Mask" "F.Paste")
			(net "M_H_CPU0_SA_DQS_DN<8>")
		)
		(pad "AF15" smd circle
			(at -21.470112 -16.560038 180)
			(size 0.450088 0.450088)
			(layers "F.Cu" "F.Mask" "F.Paste")
			(net "GND")
		)
		(pad "AF16" smd circle
			(at -20.530058 -16.560038 180)
			(size 0.450088 0.450088)
			(layers "F.Cu" "F.Mask" "F.Paste")
			(net "M_J_CPU0_SA_DQS_DN<3>")
		)
		(pad "AF17" smd circle
			(at -19.590004 -16.560038 180)
			(size 0.450088 0.450088)
			(layers "F.Cu" "F.Mask" "F.Paste")
			(net "GND")
		)
		(pad "AF18" smd circle
			(at -18.64995 -16.560038 180)
			(size 0.450088 0.450088)
			(layers "F.Cu" "F.Mask" "F.Paste")
			(net "M_J_CPU0_SA_DQS_DN<8>")
		)
		(pad "AF19" smd circle
			(at -17.709896 -16.560038 180)
			(size 0.450088 0.450088)
			(layers "F.Cu" "F.Mask" "F.Paste")
			(net "PVDDCR_SOC_P0")
		)
		(pad "AF20" smd circle
			(at -16.770096 -16.560038 180)
			(size 0.450088 0.450088)
			(layers "F.Cu" "F.Mask" "F.Paste")
			(net "M_I_CPU0_SA_DQS_DN<3>")
		)
		(pad "AF21" smd circle
			(at -15.830042 -16.560038 180)
			(size 0.450088 0.450088)
			(layers "F.Cu" "F.Mask" "F.Paste")
			(net "M_I_CPU0_SA_DQS_DN<8>")
		)
		(pad "AF22" smd circle
			(at -14.889988 -16.560038 180)
			(size 0.450088 0.450088)
			(layers "F.Cu" "F.Mask" "F.Paste")
			(net "GND")
		)
		(pad "AF23" smd circle
			(at -13.949934 -16.560038 180)
			(size 0.450088 0.450088)
			(layers "F.Cu" "F.Mask" "F.Paste")
			(net "PVDDCR_CPU0_P0")
		)
		(pad "AF24" smd circle
			(at -13.00988 -16.560038 180)
			(size 0.450088 0.450088)
			(layers "F.Cu" "F.Mask" "F.Paste")
			(net "PVDDCR_CPU0_P0")
		)
		(pad "AF25" smd circle
			(at -12.07008 -16.560038 180)
			(size 0.450088 0.450088)
			(layers "F.Cu" "F.Mask" "F.Paste")
			(net "GND")
		)
		(pad "AF26" smd circle
			(at -11.130026 -16.560038 180)
			(size 0.450088 0.450088)
			(layers "F.Cu" "F.Mask" "F.Paste")
			(net "PVDDCR_CPU0_P0")
		)
		(pad "AF27" smd circle
			(at -10.189972 -16.560038 180)
			(size 0.450088 0.450088)
			(layers "F.Cu" "F.Mask" "F.Paste")
			(net "PVDDCR_CPU0_P0")
		)
		(pad "AF28" smd circle
			(at -9.249918 -16.560038 180)
			(size 0.450088 0.450088)
			(layers "F.Cu" "F.Mask" "F.Paste")
			(net "GND")
		)
		(pad "AF29" smd circle
			(at -8.310118 -16.560038 180)
			(size 0.450088 0.450088)
			(layers "F.Cu" "F.Mask" "F.Paste")
			(net "PVDDCR_CPU0_P0")
		)
		(pad "AF30" smd circle
			(at -7.370064 -16.560038 180)
			(size 0.450088 0.450088)
			(layers "F.Cu" "F.Mask" "F.Paste")
			(net "PVDDCR_CPU0_P0")
		)
		(pad "AF31" smd circle
			(at -6.43001 -16.560038 180)
			(size 0.450088 0.450088)
			(layers "F.Cu" "F.Mask" "F.Paste")
			(net "GND")
		)
		(pad "AF32" smd circle
			(at -5.489956 -16.560038 180)
			(size 0.450088 0.450088)
			(layers "F.Cu" "F.Mask" "F.Paste")
			(net "PVDDCR_CPU0_P0")
		)
		(pad "AF33" smd circle
			(at -4.549902 -16.560038 180)
			(size 0.450088 0.450088)
			(layers "F.Cu" "F.Mask" "F.Paste")
			(net "PVDDCR_CPU0_P0")
		)
		(pad "AF34" smd circle
			(at -3.610102 -16.560038 180)
			(size 0.450088 0.450088)
			(layers "F.Cu" "F.Mask" "F.Paste")
			(net "GND")
		)
		(pad "AF35" smd circle
			(at -2.670048 -16.560038 180)
			(size 0.450088 0.450088)
			(layers "F.Cu" "F.Mask" "F.Paste")
			(net "GMI_CPU1_G0_CPU0_G2_TX_DN<15>")
		)
		(pad "AF36" smd circle
			(at -1.729994 -16.560038 180)
			(size 0.450088 0.450088)
			(layers "F.Cu" "F.Mask" "F.Paste")
			(net "GMI_CPU1_G0_CPU0_G2_TX_DP<15>")
		)
		(pad "AF37" smd circle
			(at -0.78994 -16.560038 180)
			(size 0.450088 0.450088)
			(layers "F.Cu" "F.Mask" "F.Paste")
			(net "GND")
		)
		(pad "AF39" smd circle
			(at 1.089914 -16.560038 180)
			(size 0.450088 0.450088)
			(layers "F.Cu" "F.Mask" "F.Paste")
			(net "GND")
		)
		(pad "AF40" smd circle
			(at 2.029968 -16.560038 180)
			(size 0.450088 0.450088)
			(layers "F.Cu" "F.Mask" "F.Paste")
			(net "GMI_CPU0_G0_CPU1_G2_TX_DP<0>")
		)
		(pad "AF41" smd circle
			(at 2.970022 -16.560038 180)
			(size 0.450088 0.450088)
			(layers "F.Cu" "F.Mask" "F.Paste")
			(net "GMI_CPU0_G0_CPU1_G2_TX_DN<0>")
		)
		(pad "AF42" smd circle
			(at 3.910076 -16.560038 180)
			(size 0.450088 0.450088)
			(layers "F.Cu" "F.Mask" "F.Paste")
			(net "GND")
		)
		(pad "AF43" smd circle
			(at 4.849876 -16.560038 180)
			(size 0.450088 0.450088)
			(layers "F.Cu" "F.Mask" "F.Paste")
			(net "PVDDCR_CPU0_P0")
		)
		(pad "AF44" smd circle
			(at 5.78993 -16.560038 180)
			(size 0.450088 0.450088)
			(layers "F.Cu" "F.Mask" "F.Paste")
			(net "PVDDCR_CPU0_P0")
		)
		(pad "AF45" smd circle
			(at 6.729984 -16.560038 180)
			(size 0.450088 0.450088)
			(layers "F.Cu" "F.Mask" "F.Paste")
			(net "GND")
		)
		(pad "AF46" smd circle
			(at 7.670038 -16.560038 180)
			(size 0.450088 0.450088)
			(layers "F.Cu" "F.Mask" "F.Paste")
			(net "PVDDCR_CPU0_P0")
		)
		(pad "AF47" smd circle
			(at 8.610092 -16.560038 180)
			(size 0.450088 0.450088)
			(layers "F.Cu" "F.Mask" "F.Paste")
			(net "PVDDCR_CPU0_P0")
		)
		(pad "AF48" smd circle
			(at 9.549892 -16.560038 180)
			(size 0.450088 0.450088)
			(layers "F.Cu" "F.Mask" "F.Paste")
			(net "GND")
		)
		(pad "AF49" smd circle
			(at 10.489946 -16.560038 180)
			(size 0.450088 0.450088)
			(layers "F.Cu" "F.Mask" "F.Paste")
			(net "PVDDCR_CPU0_P0")
		)
		(pad "AF50" smd circle
			(at 11.43 -16.560038 180)
			(size 0.450088 0.450088)
			(layers "F.Cu" "F.Mask" "F.Paste")
			(net "PVDDCR_CPU0_P0")
		)
		(pad "AF51" smd circle
			(at 12.370054 -16.560038 180)
			(size 0.450088 0.450088)
			(layers "F.Cu" "F.Mask" "F.Paste")
			(net "GND")
		)
		(pad "AF52" smd circle
			(at 13.310108 -16.560038 180)
			(size 0.450088 0.450088)
			(layers "F.Cu" "F.Mask" "F.Paste")
			(net "PVDDCR_CPU0_P0")
		)
		(pad "AF53" smd circle
			(at 14.249908 -16.560038 180)
			(size 0.450088 0.450088)
			(layers "F.Cu" "F.Mask" "F.Paste")
			(net "PVDDCR_CPU0_P0")
		)
		(pad "AF54" smd circle
			(at 15.189962 -16.560038 180)
			(size 0.450088 0.450088)
			(layers "F.Cu" "F.Mask" "F.Paste")
			(net "GND")
		)
		(pad "AF55" smd circle
			(at 16.130016 -16.560038 180)
			(size 0.450088 0.450088)
			(layers "F.Cu" "F.Mask" "F.Paste")
			(net "M_C_CPU0_SA_DQS_DN<8>")
		)
		(pad "AF56" smd circle
			(at 17.07007 -16.560038 180)
			(size 0.450088 0.450088)
			(layers "F.Cu" "F.Mask" "F.Paste")
			(net "M_C_CPU0_SA_DQS_DN<3>")
		)
		(pad "AF57" smd circle
			(at 18.010124 -16.560038 180)
			(size 0.450088 0.450088)
			(layers "F.Cu" "F.Mask" "F.Paste")
			(net "PVDDIO_P0")
		)
		(pad "AF58" smd circle
			(at 18.949924 -16.560038 180)
			(size 0.450088 0.450088)
			(layers "F.Cu" "F.Mask" "F.Paste")
			(net "M_D_CPU0_SA_DQS_DN<8>")
		)
		(pad "AF59" smd circle
			(at 19.889978 -16.560038 180)
			(size 0.450088 0.450088)
			(layers "F.Cu" "F.Mask" "F.Paste")
			(net "GND")
		)
		(pad "AF60" smd circle
			(at 20.830032 -16.560038 180)
			(size 0.450088 0.450088)
			(layers "F.Cu" "F.Mask" "F.Paste")
			(net "M_D_CPU0_SA_DQS_DN<3>")
		)
		(pad "AF61" smd circle
			(at 21.770086 -16.560038 180)
			(size 0.450088 0.450088)
			(layers "F.Cu" "F.Mask" "F.Paste")
			(net "GND")
		)
		(pad "AF62" smd circle
			(at 22.709886 -16.560038 180)
			(size 0.450088 0.450088)
			(layers "F.Cu" "F.Mask" "F.Paste")
			(net "M_B_CPU0_SA_DQS_DN<8>")
		)
		(pad "AF63" smd circle
			(at 23.64994 -16.560038 180)
			(size 0.450088 0.450088)
			(layers "F.Cu" "F.Mask" "F.Paste")
			(net "M_B_CPU0_SA_DQS_DN<3>")
		)
		(pad "AF64" smd circle
			(at 24.589994 -16.560038 180)
			(size 0.450088 0.450088)
			(layers "F.Cu" "F.Mask" "F.Paste")
			(net "PVDDIO_P0")
		)
		(pad "AF65" smd circle
			(at 25.530048 -16.560038 180)
			(size 0.450088 0.450088)
			(layers "F.Cu" "F.Mask" "F.Paste")
			(net "M_F_CPU0_SA_DQS_DN<8>")
		)
		(pad "AF66" smd circle
			(at 26.470102 -16.560038 180)
			(size 0.450088 0.450088)
			(layers "F.Cu" "F.Mask" "F.Paste")
			(net "GND")
		)
		(pad "AF67" smd circle
			(at 27.409902 -16.560038 180)
			(size 0.450088 0.450088)
			(layers "F.Cu" "F.Mask" "F.Paste")
			(net "M_F_CPU0_SA_DQS_DN<3>")
		)
		(pad "AF68" smd circle
			(at 28.349956 -16.560038 180)
			(size 0.450088 0.450088)
			(layers "F.Cu" "F.Mask" "F.Paste")
			(net "GND")
		)
		(pad "AF69" smd circle
			(at 29.29001 -16.560038 180)
			(size 0.450088 0.450088)
			(layers "F.Cu" "F.Mask" "F.Paste")
			(net "M_E_CPU0_SA_DQS_DN<8>")
		)
		(pad "AF70" smd circle
			(at 30.230064 -16.560038 180)
			(size 0.450088 0.450088)
			(layers "F.Cu" "F.Mask" "F.Paste")
			(net "M_E_CPU0_SA_DQS_DN<3>")
		)
		(pad "AF71" smd circle
			(at 31.170118 -16.560038 180)
			(size 0.450088 0.450088)
			(layers "F.Cu" "F.Mask" "F.Paste")
			(net "PVDDIO_P0")
		)
		(pad "AF72" smd circle
			(at 32.109918 -16.560038 180)
			(size 0.450088 0.450088)
			(layers "F.Cu" "F.Mask" "F.Paste")
			(net "M_A_CPU0_SA_DQS_DN<8>")
		)
		(pad "AF73" smd circle
			(at 33.049972 -16.560038 180)
			(size 0.450088 0.450088)
			(layers "F.Cu" "F.Mask" "F.Paste")
			(net "GND")
		)
		(pad "AF74" smd circle
			(at 33.990026 -16.560038 180)
			(size 0.450088 0.450088)
			(layers "F.Cu" "F.Mask" "F.Paste")
			(net "M_A_CPU0_SA_DQS_DN<3>")
		)
		(pad "AG1" smd circle
			(at -34.159952 -15.750032 180)
			(size 0.450088 0.450088)
			(layers "F.Cu" "F.Mask" "F.Paste")
			(net "GND")
		)
		(pad "AG2" smd circle
			(at -33.219898 -15.750032 180)
			(size 0.450088 0.450088)
			(layers "F.Cu" "F.Mask" "F.Paste")
			(net "M_G_CPU0_SA_DQ<28>")
		)
		(pad "AG3" smd circle
			(at -32.280098 -15.750032 180)
			(size 0.450088 0.450088)
			(layers "F.Cu" "F.Mask" "F.Paste")
			(net "M_G_CPU0_SA_DQS_DP<8>")
		)
		(pad "AG4" smd circle
			(at -31.340044 -15.750032 180)
			(size 0.450088 0.450088)
			(layers "F.Cu" "F.Mask" "F.Paste")
			(net "GND")
		)
		(pad "AG5" smd circle
			(at -30.39999 -15.750032 180)
			(size 0.450088 0.450088)
			(layers "F.Cu" "F.Mask" "F.Paste")
			(net "M_K_CPU0_SA_DQ<28>")
		)
		(pad "AG6" smd circle
			(at -29.459936 -15.750032 180)
			(size 0.450088 0.450088)
			(layers "F.Cu" "F.Mask" "F.Paste")
			(net "GND")
		)
		(pad "AG7" smd circle
			(at -28.519882 -15.750032 180)
			(size 0.450088 0.450088)
			(layers "F.Cu" "F.Mask" "F.Paste")
			(net "M_K_CPU0_SA_DQS_DP<8>")
		)
		(pad "AG8" smd circle
			(at -27.580082 -15.750032 180)
			(size 0.450088 0.450088)
			(layers "F.Cu" "F.Mask" "F.Paste")
			(net "GND")
		)
		(pad "AG9" smd circle
			(at -26.640028 -15.750032 180)
			(size 0.450088 0.450088)
			(layers "F.Cu" "F.Mask" "F.Paste")
			(net "M_L_CPU0_SA_DQ<28>")
		)
		(pad "AG10" smd circle
			(at -25.699974 -15.750032 180)
			(size 0.450088 0.450088)
			(layers "F.Cu" "F.Mask" "F.Paste")
			(net "M_L_CPU0_SA_DQS_DP<8>")
		)
		(pad "AG11" smd circle
			(at -24.75992 -15.750032 180)
			(size 0.450088 0.450088)
			(layers "F.Cu" "F.Mask" "F.Paste")
			(net "GND")
		)
		(pad "AG12" smd circle
			(at -23.82012 -15.750032 180)
			(size 0.450088 0.450088)
			(layers "F.Cu" "F.Mask" "F.Paste")
			(net "M_H_CPU0_SA_DQ<28>")
		)
		(pad "AG13" smd circle
			(at -22.880066 -15.750032 180)
			(size 0.450088 0.450088)
			(layers "F.Cu" "F.Mask" "F.Paste")
			(net "GND")
		)
		(pad "AG14" smd circle
			(at -21.940012 -15.750032 180)
			(size 0.450088 0.450088)
			(layers "F.Cu" "F.Mask" "F.Paste")
			(net "M_H_CPU0_SA_DQS_DP<8>")
		)
		(pad "AG15" smd circle
			(at -20.999958 -15.750032 180)
			(size 0.450088 0.450088)
			(layers "F.Cu" "F.Mask" "F.Paste")
			(net "GND")
		)
		(pad "AG16" smd circle
			(at -20.059904 -15.750032 180)
			(size 0.450088 0.450088)
			(layers "F.Cu" "F.Mask" "F.Paste")
			(net "M_J_CPU0_SA_DQ<28>")
		)
		(pad "AG17" smd circle
			(at -19.120104 -15.750032 180)
			(size 0.450088 0.450088)
			(layers "F.Cu" "F.Mask" "F.Paste")
			(net "M_J_CPU0_SA_DQS_DP<8>")
		)
		(pad "AG18" smd circle
			(at -18.18005 -15.750032 180)
			(size 0.450088 0.450088)
			(layers "F.Cu" "F.Mask" "F.Paste")
			(net "GND")
		)
		(pad "AG19" smd circle
			(at -17.239996 -15.750032 180)
			(size 0.450088 0.450088)
			(layers "F.Cu" "F.Mask" "F.Paste")
			(net "M_I_CPU0_SA_DQ<28>")
		)
		(pad "AG20" smd circle
			(at -16.299942 -15.750032 180)
			(size 0.450088 0.450088)
			(layers "F.Cu" "F.Mask" "F.Paste")
			(net "GND")
		)
		(pad "AG21" smd circle
			(at -15.359888 -15.750032 180)
			(size 0.450088 0.450088)
			(layers "F.Cu" "F.Mask" "F.Paste")
			(net "M_I_CPU0_SA_DQS_DP<8>")
		)
		(pad "AG22" smd circle
			(at -14.420088 -15.750032 180)
			(size 0.450088 0.450088)
			(layers "F.Cu" "F.Mask" "F.Paste")
			(net "GND")
		)
		(pad "AG23" smd circle
			(at -13.480034 -15.750032 180)
			(size 0.450088 0.450088)
			(layers "F.Cu" "F.Mask" "F.Paste")
			(net "GMI_CPU1_G0_CPU0_G2_TX_DN<2>")
		)
		(pad "AG24" smd circle
			(at -12.53998 -15.750032 180)
			(size 0.450088 0.450088)
			(layers "F.Cu" "F.Mask" "F.Paste")
			(net "GMI_CPU1_G0_CPU0_G2_TX_DP<2>")
		)
		(pad "AG25" smd circle
			(at -11.599926 -15.750032 180)
			(size 0.450088 0.450088)
			(layers "F.Cu" "F.Mask" "F.Paste")
			(net "GND")
		)
		(pad "AG26" smd circle
			(at -10.659872 -15.750032 180)
			(size 0.450088 0.450088)
			(layers "F.Cu" "F.Mask" "F.Paste")
			(net "GMI_CPU1_G0_CPU0_G2_TX_DN<5>")
		)
		(pad "AG27" smd circle
			(at -9.720072 -15.750032 180)
			(size 0.450088 0.450088)
			(layers "F.Cu" "F.Mask" "F.Paste")
			(net "GMI_CPU1_G0_CPU0_G2_TX_DP<5>")
		)
		(pad "AG28" smd circle
			(at -8.780018 -15.750032 180)
			(size 0.450088 0.450088)
			(layers "F.Cu" "F.Mask" "F.Paste")
			(net "GND")
		)
		(pad "AG29" smd circle
			(at -7.839964 -15.750032 180)
			(size 0.450088 0.450088)
			(layers "F.Cu" "F.Mask" "F.Paste")
			(net "GMI_CPU1_G0_CPU0_G2_TX_DN<8>")
		)
		(pad "AG30" smd circle
			(at -6.89991 -15.750032 180)
			(size 0.450088 0.450088)
			(layers "F.Cu" "F.Mask" "F.Paste")
			(net "GMI_CPU1_G0_CPU0_G2_TX_DP<8>")
		)
		(pad "AG31" smd circle
			(at -5.96011 -15.750032 180)
			(size 0.450088 0.450088)
			(layers "F.Cu" "F.Mask" "F.Paste")
			(net "GND")
		)
		(pad "AG32" smd circle
			(at -5.020056 -15.750032 180)
			(size 0.450088 0.450088)
			(layers "F.Cu" "F.Mask" "F.Paste")
			(net "GMI_CPU1_G0_CPU0_G2_TX_DN<12>")
		)
		(pad "AG33" smd circle
			(at -4.080002 -15.750032 180)
			(size 0.450088 0.450088)
			(layers "F.Cu" "F.Mask" "F.Paste")
			(net "GMI_CPU1_G0_CPU0_G2_TX_DP<12>")
		)
		(pad "AG34" smd circle
			(at -3.139948 -15.750032 180)
			(size 0.450088 0.450088)
			(layers "F.Cu" "F.Mask" "F.Paste")
			(net "GND")
		)
		(pad "AG35" smd circle
			(at -2.199894 -15.750032 180)
			(size 0.450088 0.450088)
			(layers "F.Cu" "F.Mask" "F.Paste")
			(net "PVDDCR_CPU0_P0")
		)
		(pad "AG36" smd circle
			(at -1.260094 -15.750032 180)
			(size 0.450088 0.450088)
			(layers "F.Cu" "F.Mask" "F.Paste")
			(net "PVDDCR_CPU0_P0")
		)
		(pad "AG40" smd circle
			(at 1.560068 -15.750032 180)
			(size 0.450088 0.450088)
			(layers "F.Cu" "F.Mask" "F.Paste")
			(net "PVDDCR_CPU0_P0")
		)
		(pad "AG41" smd circle
			(at 2.500122 -15.750032 180)
			(size 0.450088 0.450088)
			(layers "F.Cu" "F.Mask" "F.Paste")
			(net "PVDDCR_CPU0_P0")
		)
		(pad "AG42" smd circle
			(at 3.439922 -15.750032 180)
			(size 0.450088 0.450088)
			(layers "F.Cu" "F.Mask" "F.Paste")
			(net "GND")
		)
		(pad "AG43" smd circle
			(at 4.379976 -15.750032 180)
			(size 0.450088 0.450088)
			(layers "F.Cu" "F.Mask" "F.Paste")
			(net "GMI_CPU0_G0_CPU1_G2_TX_DP<3>")
		)
		(pad "AG44" smd circle
			(at 5.32003 -15.750032 180)
			(size 0.450088 0.450088)
			(layers "F.Cu" "F.Mask" "F.Paste")
			(net "GMI_CPU0_G0_CPU1_G2_TX_DN<3>")
		)
		(pad "AG45" smd circle
			(at 6.260084 -15.750032 180)
			(size 0.450088 0.450088)
			(layers "F.Cu" "F.Mask" "F.Paste")
			(net "GND")
		)
		(pad "AG46" smd circle
			(at 7.199884 -15.750032 180)
			(size 0.450088 0.450088)
			(layers "F.Cu" "F.Mask" "F.Paste")
			(net "GMI_CPU0_G0_CPU1_G2_TX_DP<7>")
		)
		(pad "AG47" smd circle
			(at 8.139938 -15.750032 180)
			(size 0.450088 0.450088)
			(layers "F.Cu" "F.Mask" "F.Paste")
			(net "GMI_CPU0_G0_CPU1_G2_TX_DN<7>")
		)
		(pad "AG48" smd circle
			(at 9.079992 -15.750032 180)
			(size 0.450088 0.450088)
			(layers "F.Cu" "F.Mask" "F.Paste")
			(net "GND")
		)
		(pad "AG49" smd circle
			(at 10.020046 -15.750032 180)
			(size 0.450088 0.450088)
			(layers "F.Cu" "F.Mask" "F.Paste")
			(net "GMI_CPU0_G0_CPU1_G2_TX_DP<10>")
		)
	)
)
